(kicad_pcb
	(version 20241229)
	(generator "pcbnew")
	(generator_version "9.0")
	(general
		(thickness 1.711)
		(legacy_teardrops no)
	)
	(paper "A4")
	(title_block
		(title "Antmicro Baseboard for Jetson AGX Thor")
		(date "2026-02-18")
		(rev "1.1.0")
		(company "Antmicro Ltd")
		(comment 1 "www.antmicro.com")
		(comment 9 "footprints 793-797 of 1170")
	)
	(layers
		(0 "F.Cu" signal)
		(4 "In1.Cu" signal)
		(6 "In2.Cu" signal)
		(8 "In3.Cu" signal)
		(10 "In4.Cu" jumper)
		(12 "In5.Cu" signal)
		(14 "In6.Cu" signal)
		(16 "In7.Cu" signal)
		(18 "In8.Cu" signal)
		(2 "B.Cu" signal)
		(9 "F.Adhes" user "F.Adhesive")
		(11 "B.Adhes" user "B.Adhesive")
		(13 "F.Paste" user)
		(15 "B.Paste" user)
		(5 "F.SilkS" user "F.Silkscreen")
		(7 "B.SilkS" user "B.Silkscreen")
		(1 "F.Mask" user)
		(3 "B.Mask" user)
		(17 "Dwgs.User" user "User.Drawings")
		(19 "Cmts.User" user "User.Comments")
		(21 "Eco1.User" user "User.Eco1")
		(23 "Eco2.User" user "User.Eco2")
		(25 "Edge.Cuts" user)
		(27 "Margin" user)
		(31 "F.CrtYd" user "F.Courtyard")
		(29 "B.CrtYd" user "B.Courtyard")
		(35 "F.Fab" user)
		(33 "B.Fab" user)
	)
	(footprint "antmicro-footprints:C_0402_1005Metric"
		(layer "B.Cu")
		(at 102.48 62 90)
		(descr "Capacitor SMD 0402")
		(tags "capacitor SMD 0402")
		(property "Reference" "C199"
			(at -3.6 -0.28 90)
			(layer "B.SilkS")
			(effects
				(font
					(size 0.7 0.7)
					(thickness 0.15)
				)
				(justify right top mirror)
			)
		)
		(property "Value" "C_100n_0402"
			(at -1.022927 -2.155213 90)
			(layer "B.Fab")
			(effects
				(font
					(size 0.7 0.7)
					(thickness 0.15)
				)
				(justify right top mirror)
			)
		)
		(property "Datasheet" "https://www.murata.com/products/productdetail?partno=GRM155R61H104KE14%23"
			(at 0 0 90)
			(layer "B.Fab")
			(hide yes)
			(effects
				(font
					(size 1.27 1.27)
					(thickness 0.15)
				)
				(justify mirror)
			)
		)
		(property "Description" "SMD Multilayer Ceramic Capacitor, 0.1 µF, 50 V, 0402 [1005 Metric], ± 10%, X5R, GRM Series"
			(at 0 0 90)
			(layer "B.Fab")
			(hide yes)
			(effects
				(font
					(size 1.27 1.27)
					(thickness 0.15)
				)
				(justify mirror)
			)
		)
		(property "MPN" "GRM155R61H104KE14D"
			(at 0 0 270)
			(unlocked yes)
			(layer "B.Fab")
			(hide yes)
			(effects
				(font
					(size 1 1)
					(thickness 0.15)
				)
				(justify mirror)
			)
		)
		(property "Manufacturer" "Murata"
			(at 0 0 270)
			(unlocked yes)
			(layer "B.Fab")
			(hide yes)
			(effects
				(font
					(size 1 1)
					(thickness 0.15)
				)
				(justify mirror)
			)
		)
		(property "License" "Apache-2.0"
			(at 0 0 270)
			(unlocked yes)
			(layer "B.Fab")
			(hide yes)
			(effects
				(font
					(size 1 1)
					(thickness 0.15)
				)
				(justify mirror)
			)
		)
		(property "Author" "Antmicro"
			(at 0 0 270)
			(unlocked yes)
			(layer "B.Fab")
			(hide yes)
			(effects
				(font
					(size 1 1)
					(thickness 0.15)
				)
				(justify mirror)
			)
		)
		(property "Val" "100n"
			(at 0 0 270)
			(unlocked yes)
			(layer "B.Fab")
			(hide yes)
			(effects
				(font
					(size 1 1)
					(thickness 0.15)
				)
				(justify mirror)
			)
		)
		(property "Voltage" "50V"
			(at 0 0 270)
			(unlocked yes)
			(layer "B.Fab")
			(hide yes)
			(effects
				(font
					(size 1 1)
					(thickness 0.15)
				)
				(justify mirror)
			)
		)
		(property "Dielectric" "X5R"
			(at 0 0 270)
			(unlocked yes)
			(layer "B.Fab")
			(hide yes)
			(effects
				(font
					(size 1 1)
					(thickness 0.15)
				)
				(justify mirror)
			)
		)
		(sheetname "/SoM_IO2/")
		(sheetfile "som_io2.kicad_sch")
		(attr smd)
		(fp_rect
			(start -0.925 0.47)
			(end 0.925 -0.47)
			(stroke
				(width 0.05)
				(type default)
			)
			(fill no)
			(layer "B.CrtYd")
		)
		(fp_line
			(start 0.504 -0.248)
			(end -0.494 -0.248)
			(stroke
				(width 0.15)
				(type solid)
			)
			(layer "B.Fab")
		)
		(fp_line
			(start -0.494 -0.248)
			(end -0.494 0.25)
			(stroke
				(width 0.15)
				(type solid)
			)
			(layer "B.Fab")
		)
		(fp_line
			(start 0.504 0.25)
			(end 0.504 -0.248)
			(stroke
				(width 0.15)
				(type solid)
			)
			(layer "B.Fab")
		)
		(fp_line
			(start -0.494 0.25)
			(end 0.504 0.25)
			(stroke
				(width 0.15)
				(type solid)
			)
			(layer "B.Fab")
		)
		(fp_text user "License: Apache-2.0"
			(at -0.939 -5.799 90)
			(layer "B.Fab")
			(effects
				(font
					(size 0.7 0.7)
					(thickness 0.15)
				)
				(justify right top mirror)
			)
		)
		(fp_text user "Author: Antmicro"
			(at -0.939 -3.399 90)
			(layer "B.Fab")
			(effects
				(font
					(size 0.7 0.7)
					(thickness 0.15)
				)
				(justify right top mirror)
			)
		)
		(fp_text user "${REFERENCE}"
			(at -0.939 -4.599 90)
			(layer "B.Fab")
			(effects
				(font
					(size 0.7 0.7)
					(thickness 0.15)
				)
				(justify right top mirror)
			)
		)
		(pad "1" smd roundrect
			(at -0.48 0 90)
			(size 0.59 0.64)
			(layers "B.Cu" "B.Mask" "B.Paste")
			(roundrect_rratio 0.25)
			(net 1 "GND")
			(pintype "passive")
		)
		(pad "2" smd roundrect
			(at 0.48 0 90)
			(size 0.59 0.64)
			(layers "B.Cu" "B.Mask" "B.Paste")
			(roundrect_rratio 0.25)
			(net 2 "+3V3")
			(pintype "passive")
		)
	)
	(footprint "antmicro-footprints:R_0402_1005Metric"
		(layer "B.Cu")
		(at 195.4 127.08 90)
		(descr "Resistor SMD 0402")
		(tags "resistor SMD 0402")
		(property "Reference" "R323"
			(at -1.52 -1.4 90)
			(layer "B.SilkS")
			(effects
				(font
					(size 0.7 0.7)
					(thickness 0.15)
				)
				(justify right top mirror)
			)
		)
		(property "Value" "R_10k_0402"
			(at -1.011843 -1.772046 90)
			(layer "B.Fab")
			(effects
				(font
					(size 0.7 0.7)
					(thickness 0.15)
				)
				(justify right top mirror)
			)
		)
		(property "Datasheet" "https://www.bourns.com/docs/product-datasheets/cr.pdf"
			(at 0 0 90)
			(layer "B.Fab")
			(hide yes)
			(effects
				(font
					(size 1.27 1.27)
					(thickness 0.15)
				)
				(justify mirror)
			)
		)
		(property "Description" "SMD Chip Resistor, 10 kohm, ± 1%, 62.5 mW, 0402 [1005 Metric], Thick Film, General Purpose"
			(at 0 0 90)
			(layer "B.Fab")
			(hide yes)
			(effects
				(font
					(size 1.27 1.27)
					(thickness 0.15)
				)
				(justify mirror)
			)
		)
		(property "Manufacturer" "Bourns"
			(at 0 0 270)
			(unlocked yes)
			(layer "B.Fab")
			(hide yes)
			(effects
				(font
					(size 1 1)
					(thickness 0.15)
				)
				(justify mirror)
			)
		)
		(property "MPN" "CR0402-FX-1002GLF"
			(at 0 0 270)
			(unlocked yes)
			(layer "B.Fab")
			(hide yes)
			(effects
				(font
					(size 1 1)
					(thickness 0.15)
				)
				(justify mirror)
			)
		)
		(property "Val" "10k"
			(at 0 0 270)
			(unlocked yes)
			(layer "B.Fab")
			(hide yes)
			(effects
				(font
					(size 1 1)
					(thickness 0.15)
				)
				(justify mirror)
			)
		)
		(property "License" "Apache-2.0"
			(at 0 0 270)
			(unlocked yes)
			(layer "B.Fab")
			(hide yes)
			(effects
				(font
					(size 1 1)
					(thickness 0.15)
				)
				(justify mirror)
			)
		)
		(property "Author" "Antmicro"
			(at 0 0 270)
			(unlocked yes)
			(layer "B.Fab")
			(hide yes)
			(effects
				(font
					(size 1 1)
					(thickness 0.15)
				)
				(justify mirror)
			)
		)
		(property "Tolerance" "1%"
			(at 0 0 270)
			(unlocked yes)
			(layer "B.Fab")
			(hide yes)
			(effects
				(font
					(size 1 1)
					(thickness 0.15)
				)
				(justify mirror)
			)
		)
		(sheetname "/USB Hub/")
		(sheetfile "usb_hub.kicad_sch")
		(attr smd exclude_from_pos_files exclude_from_bom dnp)
		(fp_poly
			(pts
				(xy -0.925 0.47) (xy -0.925 -0.47) (xy 0.925 -0.47) (xy 0.925 0.47)
			)
			(stroke
				(width 0.05)
				(type default)
			)
			(fill no)
			(layer "B.CrtYd")
		)
		(fp_poly
			(pts
				(xy -0.5 0.25) (xy -0.5 -0.25) (xy 0.5 -0.25) (xy 0.5 0.25)
			)
			(stroke
				(width 0.15)
				(type solid)
			)
			(fill no)
			(layer "B.Fab")
		)
		(fp_text user "License: Apache-2.0"
			(at -0.949999 -5.169 90)
			(layer "B.Fab")
			(effects
				(font
					(size 0.7 0.7)
					(thickness 0.15)
				)
				(justify right top mirror)
			)
		)
		(fp_text user "Author: Antmicro"
			(at -0.95 -4.169 90)
			(layer "B.Fab")
			(effects
				(font
					(size 0.7 0.7)
					(thickness 0.15)
				)
				(justify right top mirror)
			)
		)
		(fp_text user "${REFERENCE}"
			(at -0.95 -3.168 90)
			(layer "B.Fab")
			(effects
				(font
					(size 0.7 0.7)
					(thickness 0.15)
				)
				(justify right top mirror)
			)
		)
		(pad "1" smd roundrect
			(at -0.48 0 90)
			(size 0.59 0.64)
			(layers "B.Cu" "B.Mask" "B.Paste")
			(roundrect_rratio 0.25)
			(net 925 "/USB Hub/HUB_SPI_D0")
			(pintype "passive")
		)
		(pad "2" smd roundrect
			(at 0.48 0 90)
			(size 0.59 0.64)
			(layers "B.Cu" "B.Mask" "B.Paste")
			(roundrect_rratio 0.25)
			(net 2 "+3V3")
			(pintype "passive")
		)
	)
	(footprint "antmicro-footprints:R_0402_1005Metric"
		(layer "B.Cu")
		(at 101.24 60 90)
		(descr "Resistor SMD 0402")
		(tags "resistor SMD 0402")
		(property "Reference" "R1"
			(at -0.8 -1.24 90)
			(layer "B.SilkS")
			(effects
				(font
					(size 0.7 0.7)
					(thickness 0.15)
				)
				(justify right top mirror)
			)
		)
		(property "Value" "R_100k_0402"
			(at -1.011843 -1.772047 90)
			(layer "B.Fab")
			(effects
				(font
					(size 0.7 0.7)
					(thickness 0.15)
				)
				(justify right top mirror)
			)
		)
		(property "Datasheet" "https://www.bourns.com/docs/product-datasheets/cr.pdf"
			(at 0 0 90)
			(layer "B.Fab")
			(hide yes)
			(effects
				(font
					(size 1.27 1.27)
					(thickness 0.15)
				)
				(justify mirror)
			)
		)
		(property "Description" "SMD Chip Resistor, 100 kohm, ± 1%, 62.5 mW, 0402 [1005 Metric], Thick Film, General Purpose"
			(at 0 0 90)
			(layer "B.Fab")
			(hide yes)
			(effects
				(font
					(size 1.27 1.27)
					(thickness 0.15)
				)
				(justify mirror)
			)
		)
		(property "MPN" "CR0402-FX-1003GLF"
			(at 0 0 270)
			(unlocked yes)
			(layer "B.Fab")
			(hide yes)
			(effects
				(font
					(size 1 1)
					(thickness 0.15)
				)
				(justify mirror)
			)
		)
		(property "Manufacturer" "Bourns"
			(at 0 0 270)
			(unlocked yes)
			(layer "B.Fab")
			(hide yes)
			(effects
				(font
					(size 1 1)
					(thickness 0.15)
				)
				(justify mirror)
			)
		)
		(property "License" "Apache-2.0"
			(at 0 0 270)
			(unlocked yes)
			(layer "B.Fab")
			(hide yes)
			(effects
				(font
					(size 1 1)
					(thickness 0.15)
				)
				(justify mirror)
			)
		)
		(property "Author" "Antmicro"
			(at 0 0 270)
			(unlocked yes)
			(layer "B.Fab")
			(hide yes)
			(effects
				(font
					(size 1 1)
					(thickness 0.15)
				)
				(justify mirror)
			)
		)
		(property "Val" "100k"
			(at 0 0 270)
			(unlocked yes)
			(layer "B.Fab")
			(hide yes)
			(effects
				(font
					(size 1 1)
					(thickness 0.15)
				)
				(justify mirror)
			)
		)
		(property "Tolerance" "1%"
			(at 0 0 270)
			(unlocked yes)
			(layer "B.Fab")
			(hide yes)
			(effects
				(font
					(size 1 1)
					(thickness 0.15)
				)
				(justify mirror)
			)
		)
		(sheetname "/SoM_IO2/")
		(sheetfile "som_io2.kicad_sch")
		(attr smd)
		(fp_rect
			(start -0.925 0.47)
			(end 0.925 -0.47)
			(stroke
				(width 0.05)
				(type default)
			)
			(fill no)
			(layer "B.CrtYd")
		)
		(fp_rect
			(start -0.5 0.25)
			(end 0.5 -0.25)
			(stroke
				(width 0.15)
				(type solid)
			)
			(fill no)
			(layer "B.Fab")
		)
		(fp_text user "Author: Antmicro"
			(at -0.95 -4.169 90)
			(layer "B.Fab")
			(effects
				(font
					(size 0.7 0.7)
					(thickness 0.15)
				)
				(justify right top mirror)
			)
		)
		(fp_text user "License: Apache-2.0"
			(at -0.95 -5.169 90)
			(layer "B.Fab")
			(effects
				(font
					(size 0.7 0.7)
					(thickness 0.15)
				)
				(justify right top mirror)
			)
		)
		(fp_text user "${REFERENCE}"
			(at -0.95 -3.168 90)
			(layer "B.Fab")
			(effects
				(font
					(size 0.7 0.7)
					(thickness 0.15)
				)
				(justify right top mirror)
			)
		)
		(pad "1" smd roundrect
			(at -0.48 0 90)
			(size 0.59 0.64)
			(layers "B.Cu" "B.Mask" "B.Paste")
			(roundrect_rratio 0.25)
			(net 2 "+3V3")
			(pintype "passive")
		)
		(pad "2" smd roundrect
			(at 0.48 0 90)
			(size 0.59 0.64)
			(layers "B.Cu" "B.Mask" "B.Paste")
			(roundrect_rratio 0.25)
			(net 1101 "Net-(Y5-EN)")
			(pintype "passive")
		)
	)
	(footprint "antmicro-footprints:C_0402_1005Metric"
		(layer "B.Cu")
		(at 195.476532 137.84 -90)
		(descr "Capacitor SMD 0402")
		(tags "capacitor SMD 0402")
		(property "Reference" "C169"
			(at -0.8 0.870532 90)
			(layer "B.SilkS")
			(effects
				(font
					(size 0.7 0.7)
					(thickness 0.15)
				)
				(justify left bottom mirror)
			)
		)
		(property "Value" "C_100n_0402"
			(at -1.022927 -2.155213 90)
			(layer "B.Fab")
			(effects
				(font
					(size 0.7 0.7)
					(thickness 0.15)
				)
				(justify left bottom mirror)
			)
		)
		(property "Datasheet" "https://www.murata.com/products/productdetail?partno=GRM155R61H104KE14%23"
			(at 0 0 90)
			(layer "B.Fab")
			(hide yes)
			(effects
				(font
					(size 1.27 1.27)
					(thickness 0.15)
				)
				(justify mirror)
			)
		)
		(property "Description" "SMD Multilayer Ceramic Capacitor, 0.1 µF, 50 V, 0402 [1005 Metric], ± 10%, X5R, GRM Series"
			(at 0 0 90)
			(layer "B.Fab")
			(hide yes)
			(effects
				(font
					(size 1.27 1.27)
					(thickness 0.15)
				)
				(justify mirror)
			)
		)
		(property "MPN" "GRM155R61H104KE14D"
			(at 0 0 90)
			(unlocked yes)
			(layer "B.Fab")
			(hide yes)
			(effects
				(font
					(size 1 1)
					(thickness 0.15)
				)
				(justify mirror)
			)
		)
		(property "Manufacturer" "Murata"
			(at 0 0 90)
			(unlocked yes)
			(layer "B.Fab")
			(hide yes)
			(effects
				(font
					(size 1 1)
					(thickness 0.15)
				)
				(justify mirror)
			)
		)
		(property "License" "Apache-2.0"
			(at 0 0 90)
			(unlocked yes)
			(layer "B.Fab")
			(hide yes)
			(effects
				(font
					(size 1 1)
					(thickness 0.15)
				)
				(justify mirror)
			)
		)
		(property "Author" "Antmicro"
			(at 0 0 90)
			(unlocked yes)
			(layer "B.Fab")
			(hide yes)
			(effects
				(font
					(size 1 1)
					(thickness 0.15)
				)
				(justify mirror)
			)
		)
		(property "Val" "100n"
			(at 0 0 90)
			(unlocked yes)
			(layer "B.Fab")
			(hide yes)
			(effects
				(font
					(size 1 1)
					(thickness 0.15)
				)
				(justify mirror)
			)
		)
		(property "Voltage" "50V"
			(at 0 0 90)
			(unlocked yes)
			(layer "B.Fab")
			(hide yes)
			(effects
				(font
					(size 1 1)
					(thickness 0.15)
				)
				(justify mirror)
			)
		)
		(property "Dielectric" "X5R"
			(at 0 0 90)
			(unlocked yes)
			(layer "B.Fab")
			(hide yes)
			(effects
				(font
					(size 1 1)
					(thickness 0.15)
				)
				(justify mirror)
			)
		)
		(sheetname "/SFP/")
		(sheetfile "sfp.kicad_sch")
		(attr smd)
		(fp_rect
			(start -0.925 0.47)
			(end 0.925 -0.47)
			(stroke
				(width 0.05)
				(type default)
			)
			(fill no)
			(layer "B.CrtYd")
		)
		(fp_line
			(start -0.494 0.25)
			(end 0.504 0.25)
			(stroke
				(width 0.15)
				(type solid)
			)
			(layer "B.Fab")
		)
		(fp_line
			(start 0.504 0.25)
			(end 0.504 -0.248)
			(stroke
				(width 0.15)
				(type solid)
			)
			(layer "B.Fab")
		)
		(fp_line
			(start -0.494 -0.248)
			(end -0.494 0.25)
			(stroke
				(width 0.15)
				(type solid)
			)
			(layer "B.Fab")
		)
		(fp_line
			(start 0.504 -0.248)
			(end -0.494 -0.248)
			(stroke
				(width 0.15)
				(type solid)
			)
			(layer "B.Fab")
		)
		(fp_text user "License: Apache-2.0"
			(at -0.939 -5.799 90)
			(layer "B.Fab")
			(effects
				(font
					(size 0.7 0.7)
					(thickness 0.15)
				)
				(justify left bottom mirror)
			)
		)
		(fp_text user "Author: Antmicro"
			(at -0.939 -3.399 90)
			(layer "B.Fab")
			(effects
				(font
					(size 0.7 0.7)
					(thickness 0.15)
				)
				(justify left bottom mirror)
			)
		)
		(fp_text user "${REFERENCE}"
			(at -0.939 -4.599 90)
			(layer "B.Fab")
			(effects
				(font
					(size 0.7 0.7)
					(thickness 0.15)
				)
				(justify left bottom mirror)
			)
		)
		(pad "1" smd roundrect
			(at -0.48 0 270)
			(size 0.59 0.64)
			(layers "B.Cu" "B.Mask" "B.Paste")
			(roundrect_rratio 0.25)
			(net 1 "GND")
			(pintype "passive")
		)
		(pad "2" smd roundrect
			(at 0.48 0 270)
			(size 0.59 0.64)
			(layers "B.Cu" "B.Mask" "B.Paste")
			(roundrect_rratio 0.25)
			(net 379 "/SFP/SH")
			(pintype "passive")
		)
	)
	(footprint "antmicro-footprints:C_0402_1005Metric"
		(layer "B.Cu")
		(at 131 132 -90)
		(descr "Capacitor SMD 0402")
		(tags "capacitor SMD 0402")
		(property "Reference" "C189"
			(at -4 -0.41 90)
			(layer "B.SilkS")
			(effects
				(font
					(size 0.7 0.7)
					(thickness 0.15)
				)
				(justify left bottom mirror)
			)
		)
		(property "Value" "C_100n_0402"
			(at -1.022927 -2.155213 90)
			(layer "B.Fab")
			(effects
				(font
					(size 0.7 0.7)
					(thickness 0.15)
				)
				(justify left bottom mirror)
			)
		)
		(property "Datasheet" "https://www.murata.com/products/productdetail?partno=GRM155R61H104KE14%23"
			(at 0 0 90)
			(layer "B.Fab")
			(hide yes)
			(effects
				(font
					(size 1.27 1.27)
					(thickness 0.15)
				)
				(justify mirror)
			)
		)
		(property "Description" "SMD Multilayer Ceramic Capacitor, 0.1 µF, 50 V, 0402 [1005 Metric], ± 10%, X5R, GRM Series"
			(at 0 0 90)
			(layer "B.Fab")
			(hide yes)
			(effects
				(font
					(size 1.27 1.27)
					(thickness 0.15)
				)
				(justify mirror)
			)
		)
		(property "Manufacturer" "Murata"
			(at 0 0 90)
			(unlocked yes)
			(layer "B.Fab")
			(hide yes)
			(effects
				(font
					(size 1 1)
					(thickness 0.15)
				)
				(justify mirror)
			)
		)
		(property "MPN" "GRM155R61H104KE14D"
			(at 0 0 90)
			(unlocked yes)
			(layer "B.Fab")
			(hide yes)
			(effects
				(font
					(size 1 1)
					(thickness 0.15)
				)
				(justify mirror)
			)
		)
		(property "Val" "100n"
			(at 0 0 90)
			(unlocked yes)
			(layer "B.Fab")
			(hide yes)
			(effects
				(font
					(size 1 1)
					(thickness 0.15)
				)
				(justify mirror)
			)
		)
		(property "License" "Apache-2.0"
			(at 0 0 90)
			(unlocked yes)
			(layer "B.Fab")
			(hide yes)
			(effects
				(font
					(size 1 1)
					(thickness 0.15)
				)
				(justify mirror)
			)
		)
		(property "Author" "Antmicro"
			(at 0 0 90)
			(unlocked yes)
			(layer "B.Fab")
			(hide yes)
			(effects
				(font
					(size 1 1)
					(thickness 0.15)
				)
				(justify mirror)
			)
		)
		(property "Voltage" "50V"
			(at 0 0 90)
			(unlocked yes)
			(layer "B.Fab")
			(hide yes)
			(effects
				(font
					(size 1 1)
					(thickness 0.15)
				)
				(justify mirror)
			)
		)
		(property "Dielectric" "X5R"
			(at 0 0 90)
			(unlocked yes)
			(layer "B.Fab")
			(hide yes)
			(effects
				(font
					(size 1 1)
					(thickness 0.15)
				)
				(justify mirror)
			)
		)
		(sheetname "/M.2/")
		(sheetfile "m2.kicad_sch")
		(attr smd)
		(fp_poly
			(pts
				(xy -0.925 0.47) (xy 0.925 0.47) (xy 0.925 -0.47) (xy -0.925 -0.47)
			)
			(stroke
				(width 0.05)
				(type default)
			)
			(fill no)
			(layer "B.CrtYd")
		)
		(fp_line
			(start -0.494 0.25)
			(end 0.504 0.25)
			(stroke
				(width 0.15)
				(type solid)
			)
			(layer "B.Fab")
		)
		(fp_line
			(start 0.504 0.25)
			(end 0.504 -0.248)
			(stroke
				(width 0.15)
				(type solid)
			)
			(layer "B.Fab")
		)
		(fp_line
			(start -0.494 -0.248)
			(end -0.494 0.25)
			(stroke
				(width 0.15)
				(type solid)
			)
			(layer "B.Fab")
		)
		(fp_line
			(start 0.504 -0.248)
			(end -0.494 -0.248)
			(stroke
				(width 0.15)
				(type solid)
			)
			(layer "B.Fab")
		)
		(fp_text user "Author: Antmicro"
			(at -0.939 -3.399 90)
			(layer "B.Fab")
			(effects
				(font
					(size 0.7 0.7)
					(thickness 0.15)
				)
				(justify left bottom mirror)
			)
		)
		(fp_text user "${REFERENCE}"
			(at -0.939 -4.599 90)
			(layer "B.Fab")
			(effects
				(font
					(size 0.7 0.7)
					(thickness 0.15)
				)
				(justify left bottom mirror)
			)
		)
		(fp_text user "License: Apache-2.0"
			(at -0.939 -5.799 90)
			(layer "B.Fab")
			(effects
				(font
					(size 0.7 0.7)
					(thickness 0.15)
				)
				(justify left bottom mirror)
			)
		)
		(pad "1" smd roundrect
			(at -0.48 0 270)
			(size 0.59 0.64)
			(layers "B.Cu" "B.Mask" "B.Paste")
			(roundrect_rratio 0.25)
			(net 2 "+3V3")
			(pintype "passive")
		)
		(pad "2" smd roundrect
			(at 0.48 0 270)
			(size 0.59 0.64)
			(layers "B.Cu" "B.Mask" "B.Paste")
			(roundrect_rratio 0.25)
			(net 1 "GND")
			(pintype "passive")
		)
	)
)
